FILE_TYPE = MACRO_DRAWING;
SET COLOR_WIRE YELLOW;
SET COLOR_PROP ORANGE;
SET COLOR_DOT WHITE;
SET COLOR_ARC YELLOW;
SET COLOR_BODY GREEN;
SET COLOR_NOTE PURPLE;
SET PROP_DISPLAY VALUE;
SET PAGE_NUMBER P61;
FORCEADD QUANTA_TITLE_BLOCK_C..1
(0 0);
FORCEPROP 1 LAST CUSTOM_TXT_CDS <NAME_2>
J 0
(-3175 50);
FORCEPROP 1 LAST CUSTOM_TXT_CDS <NAME_1>
J 0
(-3175 175);
FORCEPROP 1 LAST CUSTOM_TXT_CDS <Q_NUMBER>
J 0
(-1403 103);
DISPLAY 1.212766 (-1403 103);
FORCEPROP 1 LAST CUSTOM_TXT_CDS <Q_PROJ>
J 0
(-2382 102);
DISPLAY 1.212766 (-2382 102);
FORCEPROP 1 LAST CUSTOM_TXT_CDS <Q_REV>
J 0
(-184 103);
DISPLAY 1.212766 (-184 103);
FORCEPROP 1 LAST CUSTOM_TXT_CDS <CON_LAST_MODIFIED>
J 0
(-1885 15);
DISPLAY 0.978723 (-1885 15);
FORCEPROP 1 LAST CUSTOM_TXT_CDS <CON_PAGE_NUM> OF <CON_TOTAL_PAGES>
J 0
(-446 18);
DISPLAY 0.978723 (-446 18);
FORCEPROP 1 LAST Q_TITLE CPU1 GLUE LOGIC
J 0
(-9300 75);
DISPLAY 2.446809 (-9300 75);
PAINT GREEN (-9300 75);
FORCEPROP 2 LAST PAGE_BORDER TRUE
J 0
(-7890 5250);
DISPLAY 0.638298 (-7890 5250);
PAINT PINK (-7890 5250);
DISPLAY INVISIBLE (-7890 5250);
FORCEPROP 2 LAST CDS_LIB pure_quanta
J 0
(0 0);
DISPLAY INVISIBLE (0 0);
FORCEPROP 1 LAST CDS_LMAN_SYM_OUTLINE -9475,6775,100,-125
J 0
(0 0);
DISPLAY 0.468085 (0 0);
PAINT GREEN (0 0);
DISPLAY INVISIBLE (0 0);
FORCEPROP 2 LAST CDS_XR_PAGE_TITLE CR-61 : @T6G_MB_LIB.T6G(SCH_1):PAGE61
J 0
(-7890 5250);
DISPLAY 0.638298 (-7890 5250);
PAINT PINK (-7890 5250);
DISPLAY INVISIBLE (-7890 5250);
FORCEPROP 2 LAST CUSTOM_TXT_CDS <XR_PAGE_TITLE>
J 0
(-7890 5250);
DISPLAY 0.638298 (-7890 5250);
PAINT PINK (-7890 5250);
DISPLAY INVISIBLE (-7890 5250);
FORCEPROP 1 LAST COMMENT_BODY TRUE
J 0
(12 -13);
DISPLAY 0.978723 (12 -13);
PAINT GREEN (12 -13);
DISPLAY INVISIBLE (12 -13);
FORCEPROP 1 LAST Q_DEPT BU9
J 1
(-3763 49);
DISPLAY 1.957447 (-3763 49);
PAINT GREEN (-3763 49);
DISPLAY INVISIBLE (-3763 49);
FORCEPROP 0 LAST CDS_CON_LAST_MODIFIED Thu Aug 24 10:13:55 2023
J 0
(-1885 15);
DISPLAY INVISIBLE (-1885 15);
QUIT
